# S9S_MB_2U (Grand Teton) — schematic netlist excerpt (pin names and nets, part order shuffled) for the footprints in the layout excerpt that follows; sources: Cadence DE-HDL packaged netlist, KiCad conversion of 03242023_DA0F0TMBIJ0_F0T_Motherboard_J_brd_V01_OCP.brd

R4162  Q_RES  54.9K 1% EMPTY  pkg 0402LF  page 145 : A = P3V3_AUX ; B = GPU_3V3IO_RSVD3
R3089  Q_RES  130 1% CHIP  pkg 0402LF  page 253 : A = LED_PWRGD_PVCCFA_EHV_CPU0 ; B = P3V3_AUX

(kicad_pcb
	(version 20260206)
	(generator "pcbnew")
	(generator_version "10.0")
	(general
		(thickness 1.6)
		(legacy_teardrops no)
	)
	(paper "A4")
	(title_block
		(title "03242023_DA0F0TMBIJ0_F0T_Motherboard_J_brd_V01_OCP.brd")
		(comment 1 "Grand Teton / footprints 1018-1019 of 6105")
	)
	(layers
		(0 "F.Cu" signal "TOP")
		(4 "In1.Cu" signal "GND")
		(6 "In2.Cu" signal "IN1")
		(8 "In3.Cu" signal "GND1")
		(10 "In4.Cu" signal "IN2")
		(12 "In5.Cu" signal "GND2")
		(14 "In6.Cu" signal "IN3")
		(16 "In7.Cu" signal "GND3")
		(18 "In8.Cu" signal "VCC")
		(20 "In9.Cu" signal "VCC1")
		(22 "In10.Cu" signal "GND4")
		(24 "In11.Cu" signal "IN4")
		(26 "In12.Cu" signal "GND5")
		(28 "In13.Cu" signal "IN5")
		(30 "In14.Cu" signal "GND6")
		(32 "In15.Cu" signal "IN6")
		(34 "In16.Cu" signal "GND7")
		(2 "B.Cu" signal "BOTTOM")
		(9 "F.Adhes" user "F.Adhesive")
		(11 "B.Adhes" user "B.Adhesive")
		(13 "F.Paste" user "Package Geometry/Pastemask Top")
		(15 "B.Paste" user "Package Geometry/Pastemask Bottom")
		(5 "F.SilkS" user "Ref Des/Silkscreen Top")
		(7 "B.SilkS" user "Ref Des/Silkscreen Bottom")
		(1 "F.Mask" user "Board Geometry/Soldermask Top")
		(3 "B.Mask" user "Board Geometry/Soldermask Bottom")
		(17 "Dwgs.User" user "User.Drawings")
		(19 "Cmts.User" user "User.Comments")
		(21 "Eco1.User" user "User.Eco1")
		(23 "Eco2.User" user "User.Eco2")
		(25 "Edge.Cuts" user "Board Geometry/Outline")
		(27 "Margin" user)
		(31 "F.CrtYd" user "Package Geometry/Place Bound Top")
		(29 "B.CrtYd" user "Package Geometry/Place Bound Bottom")
		(35 "F.Fab" user "Ref Des/Assembly Top")
		(33 "B.Fab" user "Ref Des/Assembly Bottom")
	)
	(footprint ""
		(layer "F.Cu")
		(at 75.738736 -74.901552 -90)
		(property "Reference" "R3089"
			(at 0 0 270)
			(layer "F.SilkS")
			(hide yes)
			(effects
				(font
					(size 1.27 1.27)
				)
			)
		)
		(property "Value" ""
			(at 0 0 270)
			(layer "F.Fab")
			(effects
				(font
					(size 1.27 1.27)
				)
			)
		)
		(duplicate_pad_numbers_are_jumpers no)
		(fp_line
			(start -0.7874 0.4064)
			(end -0.7874 -0.4064)
			(stroke
				(width 0.1524)
				(type default)
			)
			(layer "F.SilkS")
		)
		(fp_line
			(start 0.7874 0.4064)
			(end -0.7874 0.4064)
			(stroke
				(width 0.1524)
				(type default)
			)
			(layer "F.SilkS")
		)
		(fp_line
			(start -0.7874 -0.4064)
			(end 0.7874 -0.4064)
			(stroke
				(width 0.1524)
				(type default)
			)
			(layer "F.SilkS")
		)
		(fp_line
			(start 0.7874 -0.4064)
			(end 0.7874 0.4064)
			(stroke
				(width 0.1524)
				(type default)
			)
			(layer "F.SilkS")
		)
		(fp_line
			(start -0.67945 0.3048)
			(end -0.67945 -0.305054)
			(stroke
				(width 0.1)
				(type default)
			)
			(layer "F.Fab")
		)
		(fp_line
			(start -0.12065 0.3048)
			(end -0.67945 0.3048)
			(stroke
				(width 0.1)
				(type default)
			)
			(layer "F.Fab")
		)
		(fp_line
			(start 0.120396 0.3048)
			(end 0.120396 0.2794)
			(stroke
				(width 0.1)
				(type default)
			)
			(layer "F.Fab")
		)
		(fp_line
			(start 0.67945 0.3048)
			(end 0.120396 0.3048)
			(stroke
				(width 0.1)
				(type default)
			)
			(layer "F.Fab")
		)
		(fp_line
			(start -0.12065 0.2794)
			(end -0.12065 0.3048)
			(stroke
				(width 0.1)
				(type default)
			)
			(layer "F.Fab")
		)
		(fp_line
			(start 0.120396 0.2794)
			(end -0.12065 0.2794)
			(stroke
				(width 0.1)
				(type default)
			)
			(layer "F.Fab")
		)
		(fp_line
			(start -0.12065 -0.2794)
			(end 0.12065 -0.2794)
			(stroke
				(width 0.1)
				(type default)
			)
			(layer "F.Fab")
		)
		(fp_line
			(start 0.12065 -0.2794)
			(end 0.12065 -0.3048)
			(stroke
				(width 0.1)
				(type default)
			)
			(layer "F.Fab")
		)
		(fp_line
			(start 0.12065 -0.3048)
			(end 0.67945 -0.3048)
			(stroke
				(width 0.1)
				(type default)
			)
			(layer "F.Fab")
		)
		(fp_line
			(start 0.67945 -0.3048)
			(end 0.67945 0.3048)
			(stroke
				(width 0.1)
				(type default)
			)
			(layer "F.Fab")
		)
		(fp_line
			(start -0.67945 -0.305054)
			(end -0.12065 -0.305054)
			(stroke
				(width 0.1)
				(type default)
			)
			(layer "F.Fab")
		)
		(fp_line
			(start -0.12065 -0.305054)
			(end -0.12065 -0.2794)
			(stroke
				(width 0.1)
				(type default)
			)
			(layer "F.Fab")
		)
		(pad "1" smd circle
			(at -0.40005 0 270)
			(size 0 0)
			(layers "F.Cu" "F.Mask" "F.Paste")
			(net "LED_PWRGD_PVCCFA_EHV_CPU0")
		)
		(pad "2" smd circle
			(at 0.40005 0 270)
			(size 0 0)
			(layers "F.Cu" "F.Mask" "F.Paste")
			(net "P3V3_AUX")
		)
	)
	(footprint ""
		(layer "F.Cu")
		(at 360.444542 -390.43737)
		(property "Reference" "R4162"
			(at 0 0 0)
			(layer "F.SilkS")
			(hide yes)
			(effects
				(font
					(size 1.27 1.27)
				)
			)
		)
		(property "Value" ""
			(at 0 0 0)
			(layer "F.Fab")
			(effects
				(font
					(size 1.27 1.27)
				)
			)
		)
		(duplicate_pad_numbers_are_jumpers no)
		(fp_line
			(start -0.7874 -0.4064)
			(end 0.7874 -0.4064)
			(stroke
				(width 0.1524)
				(type default)
			)
			(layer "F.SilkS")
		)
		(fp_line
			(start -0.7874 0.4064)
			(end -0.7874 -0.4064)
			(stroke
				(width 0.1524)
				(type default)
			)
			(layer "F.SilkS")
		)
		(fp_line
			(start 0.7874 -0.4064)
			(end 0.7874 0.4064)
			(stroke
				(width 0.1524)
				(type default)
			)
			(layer "F.SilkS")
		)
		(fp_line
			(start 0.7874 0.4064)
			(end -0.7874 0.4064)
			(stroke
				(width 0.1524)
				(type default)
			)
			(layer "F.SilkS")
		)
		(fp_line
			(start -0.67945 -0.305054)
			(end -0.12065 -0.305054)
			(stroke
				(width 0.1)
				(type default)
			)
			(layer "F.Fab")
		)
		(fp_line
			(start -0.67945 0.3048)
			(end -0.67945 -0.305054)
			(stroke
				(width 0.1)
				(type default)
			)
			(layer "F.Fab")
		)
		(fp_line
			(start -0.12065 -0.305054)
			(end -0.12065 -0.2794)
			(stroke
				(width 0.1)
				(type default)
			)
			(layer "F.Fab")
		)
		(fp_line
			(start -0.12065 -0.2794)
			(end 0.12065 -0.2794)
			(stroke
				(width 0.1)
				(type default)
			)
			(layer "F.Fab")
		)
		(fp_line
			(start -0.12065 0.2794)
			(end -0.12065 0.3048)
			(stroke
				(width 0.1)
				(type default)
			)
			(layer "F.Fab")
		)
		(fp_line
			(start -0.12065 0.3048)
			(end -0.67945 0.3048)
			(stroke
				(width 0.1)
				(type default)
			)
			(layer "F.Fab")
		)
		(fp_line
			(start 0.120396 0.2794)
			(end -0.12065 0.2794)
			(stroke
				(width 0.1)
				(type default)
			)
			(layer "F.Fab")
		)
		(fp_line
			(start 0.120396 0.3048)
			(end 0.120396 0.2794)
			(stroke
				(width 0.1)
				(type default)
			)
			(layer "F.Fab")
		)
		(fp_line
			(start 0.12065 -0.3048)
			(end 0.67945 -0.3048)
			(stroke
				(width 0.1)
				(type default)
			)
			(layer "F.Fab")
		)
		(fp_line
			(start 0.12065 -0.2794)
			(end 0.12065 -0.3048)
			(stroke
				(width 0.1)
				(type default)
			)
			(layer "F.Fab")
		)
		(fp_line
			(start 0.67945 -0.3048)
			(end 0.67945 0.3048)
			(stroke
				(width 0.1)
				(type default)
			)
			(layer "F.Fab")
		)
		(fp_line
			(start 0.67945 0.3048)
			(end 0.120396 0.3048)
			(stroke
				(width 0.1)
				(type default)
			)
			(layer "F.Fab")
		)
		(pad "1" smd circle
			(at -0.40005 0)
			(size 0 0)
			(layers "F.Cu" "F.Mask" "F.Paste")
			(net "P3V3_AUX")
		)
		(pad "2" smd circle
			(at 0.40005 0)
			(size 0 0)
			(layers "F.Cu" "F.Mask" "F.Paste")
			(net "GPU_3V3IO_RSVD3")
		)
	)
)
